(
  (version 16.5)
  (tool
    (creator "conceptHDL")
    (last "conceptHDL")
  )
  (library "mstr_symbols")
  (design "gnd"
    (lastIds
      (lastNetId 4)
    )
    (nets
      ("N1" "a" -1 -1 1 3)
      ("N2" "page1_a" -1 -1 0 )
      ("N4" "page1_gnd" -1 -1 0 )
      ("N3" "gnd" -1 -1 2 )
    )

    (alias
      ("N2" -1 -1 "N1" -1 -1)
      ("N4" -1 -1 "N2" -1 -1)
      ("N4" -1 -1 "N3" -1 -1)
    )

  )
)
